(kicad_pcb
	(version 20260206)
	(generator "pcbnew")
	(generator_version "10.0")
	(general
		(thickness 1.6)
		(legacy_teardrops no)
	)
	(paper "A4")
	(title_block
		(title "Bryce Canyon_R.DPB_16317-1_OCP.brd")
		(comment 1 "Bryce Canyon / footprints 314-320 of 2099")
	)
	(layers
		(0 "F.Cu" signal "TOP")
		(4 "In1.Cu" signal "L2GND")
		(6 "In2.Cu" signal "L3")
		(8 "In3.Cu" signal "L4VCC")
		(10 "In4.Cu" signal "L5VCC")
		(12 "In5.Cu" signal "L6")
		(14 "In6.Cu" signal "L7GND")
		(2 "B.Cu" signal "BOTTOM")
		(9 "F.Adhes" user "F.Adhesive")
		(11 "B.Adhes" user "B.Adhesive")
		(13 "F.Paste" user "Package Geometry/Pastemask Top")
		(15 "B.Paste" user "Package Geometry/Pastemask Bottom")
		(5 "F.SilkS" user "Ref Des/Silkscreen Top")
		(7 "B.SilkS" user "Ref Des/Silkscreen Bottom")
		(1 "F.Mask" user "Board Geometry/Soldermask Top")
		(3 "B.Mask" user "Board Geometry/Soldermask Bottom")
		(17 "Dwgs.User" user "User.Drawings")
		(19 "Cmts.User" user "User.Comments")
		(21 "Eco1.User" user "User.Eco1")
		(23 "Eco2.User" user "User.Eco2")
		(25 "Edge.Cuts" user "Board Geometry/Outline")
		(27 "Margin" user)
		(31 "F.CrtYd" user "Package Geometry/Place Bound Top")
		(29 "B.CrtYd" user "Package Geometry/Place Bound Bottom")
		(35 "F.Fab" user "Ref Des/Assembly Top")
		(33 "B.Fab" user "Ref Des/Assembly Bottom")
	)
	(footprint ""
		(layer "F.Cu")
		(at 126.9746 -31.623)
		(property "Reference" "C388"
			(at 0 0 0)
			(layer "F.SilkS")
			(hide yes)
			(effects
				(font
					(size 1.27 1.27)
				)
			)
		)
		(property "Value" "SCD01U50V2KX-1GP"
			(at 1.1811 -2.7051 0)
			(unlocked yes)
			(layer "F.Fab")
			(hide yes)
			(effects
				(font
					(size 1.016 1.016)
					(thickness 0.1524)
				)
			)
		)
		(property "Device Type" "C402H22"
			(at 1.1811 -4.2291 0)
			(unlocked yes)
			(layer "F.Fab")
			(hide yes)
			(effects
				(font
					(size 1.016 1.016)
					(thickness 0.1524)
				)
			)
		)
		(duplicate_pad_numbers_are_jumpers no)
		(fp_rect
			(start -0.4318 0.9525)
			(end 0.4318 -0.9525)
			(stroke
				(width 0)
				(type default)
			)
			(fill no)
			(layer "F.CrtYd")
		)
		(fp_rect
			(start -0.4318 0.9525)
			(end 0.4318 -0.9525)
			(stroke
				(width 0)
				(type default)
			)
			(fill no)
			(layer "F.Fab")
		)
		(pad "1" smd custom
			(at 0 -0.4445)
			(size 0.1524 0.1524)
			(layers "F.Cu" "F.Mask" "F.Paste")
			(net "HDD_PRSNT_27")
			(options
				(clearance outline)
				(anchor circle)
			)
			(primitives
				(gr_poly
					(pts
						(arc
							(start 0.3048 -0.2032)
							(mid 0.275042 -0.275042)
							(end 0.2032 -0.3048)
						)
						(arc
							(start -0.2032 -0.3048)
							(mid -0.275042 -0.275042)
							(end -0.3048 -0.2032)
						)
						(arc
							(start -0.3048 0.2032)
							(mid -0.275042 0.275042)
							(end -0.2032 0.3048)
						)
						(arc
							(start 0.2032 0.3048)
							(mid 0.275042 0.275042)
							(end 0.3048 0.2032)
						)
					)
					(width 0)
					(fill yes)
				)
			)
		)
		(pad "2" smd custom
			(at 0 0.4445)
			(size 0.1524 0.1524)
			(layers "F.Cu" "F.Mask" "F.Paste")
			(net "GND")
			(options
				(clearance outline)
				(anchor circle)
			)
			(primitives
				(gr_poly
					(pts
						(arc
							(start 0.3048 -0.2032)
							(mid 0.275042 -0.275042)
							(end 0.2032 -0.3048)
						)
						(arc
							(start -0.2032 -0.3048)
							(mid -0.275042 -0.275042)
							(end -0.3048 -0.2032)
						)
						(arc
							(start -0.3048 0.2032)
							(mid -0.275042 0.275042)
							(end -0.2032 0.3048)
						)
						(arc
							(start 0.2032 0.3048)
							(mid 0.275042 0.275042)
							(end 0.3048 0.2032)
						)
					)
					(width 0)
					(fill yes)
				)
			)
		)
	)
	(footprint ""
		(layer "F.Cu")
		(at 464.566 -27.813 -90)
		(property "Reference" "R865"
			(at 0 0 270)
			(layer "F.SilkS")
			(hide yes)
			(effects
				(font
					(size 1.27 1.27)
				)
			)
		)
		(property "Value" "300KR2F-GP"
			(at 0.064008 -3.993896 270)
			(unlocked yes)
			(layer "F.Fab")
			(hide yes)
			(effects
				(font
					(size 1.016 1.016)
					(thickness 0.1524)
				)
			)
		)
		(property "Device Type" "R402H16"
			(at 0.064008 -5.517896 270)
			(unlocked yes)
			(layer "F.Fab")
			(hide yes)
			(effects
				(font
					(size 1.016 1.016)
					(thickness 0.1524)
				)
			)
		)
		(duplicate_pad_numbers_are_jumpers no)
		(fp_line
			(start -0.508 -0.9398)
			(end -0.508 0.9398)
			(stroke
				(width 0.1524)
				(type default)
			)
			(layer "F.SilkS")
		)
		(fp_line
			(start 0.508 -0.9398)
			(end -0.508 -0.9398)
			(stroke
				(width 0.1524)
				(type default)
			)
			(layer "F.SilkS")
		)
		(fp_rect
			(start -0.508 0.9398)
			(end 0.508 -0.9398)
			(stroke
				(width 0)
				(type default)
			)
			(fill no)
			(layer "F.CrtYd")
		)
		(fp_rect
			(start -0.508 0.9398)
			(end 0.508 -0.9398)
			(stroke
				(width 0)
				(type default)
			)
			(fill no)
			(layer "F.Fab")
		)
		(pad "1" smd custom
			(at 0 -0.4445 270)
			(size 0.1397 0.1397)
			(layers "F.Cu" "F.Mask" "F.Paste")
			(net "SW_HDD_N34")
			(options
				(clearance outline)
				(anchor circle)
			)
			(primitives
				(gr_poly
					(pts
						(arc
							(start -0.1778 -0.2794)
							(mid -0.249642 -0.249642)
							(end -0.2794 -0.1778)
						)
						(arc
							(start -0.2794 0.1778)
							(mid -0.249642 0.249642)
							(end -0.1778 0.2794)
						)
						(arc
							(start 0.1778 0.2794)
							(mid 0.249642 0.249642)
							(end 0.2794 0.1778)
						)
						(arc
							(start 0.2794 -0.1778)
							(mid 0.249642 -0.249642)
							(end 0.1778 -0.2794)
						)
					)
					(width 0)
					(fill yes)
				)
			)
		)
		(pad "2" smd custom
			(at 0 0.4445 270)
			(size 0.1397 0.1397)
			(layers "F.Cu" "F.Mask" "F.Paste")
			(net "P12V_B")
			(options
				(clearance outline)
				(anchor circle)
			)
			(primitives
				(gr_poly
					(pts
						(arc
							(start -0.1778 -0.2794)
							(mid -0.249642 -0.249642)
							(end -0.2794 -0.1778)
						)
						(arc
							(start -0.2794 0.1778)
							(mid -0.249642 0.249642)
							(end -0.1778 0.2794)
						)
						(arc
							(start 0.1778 0.2794)
							(mid 0.249642 0.249642)
							(end 0.2794 0.1778)
						)
						(arc
							(start 0.2794 -0.1778)
							(mid 0.249642 -0.249642)
							(end 0.1778 -0.2794)
						)
					)
					(width 0)
					(fill yes)
				)
			)
		)
	)
	(footprint ""
		(layer "F.Cu")
		(at 473.202 -129.286)
		(property "Reference" "R611"
			(at 0 0 0)
			(layer "F.SilkS")
			(hide yes)
			(effects
				(font
					(size 1.27 1.27)
				)
			)
		)
		(property "Value" "4K7R2F-GP"
			(at 0.064008 -3.993896 0)
			(unlocked yes)
			(layer "F.Fab")
			(hide yes)
			(effects
				(font
					(size 1.016 1.016)
					(thickness 0.1524)
				)
			)
		)
		(property "Device Type" "R402H16"
			(at 0.064008 -5.517896 0)
			(unlocked yes)
			(layer "F.Fab")
			(hide yes)
			(effects
				(font
					(size 1.016 1.016)
					(thickness 0.1524)
				)
			)
		)
		(duplicate_pad_numbers_are_jumpers no)
		(fp_line
			(start -0.508 -0.9398)
			(end -0.508 0.9398)
			(stroke
				(width 0.1524)
				(type default)
			)
			(layer "F.SilkS")
		)
		(fp_line
			(start 0.508 -0.9398)
			(end -0.508 -0.9398)
			(stroke
				(width 0.1524)
				(type default)
			)
			(layer "F.SilkS")
		)
		(fp_rect
			(start -0.508 0.9398)
			(end 0.508 -0.9398)
			(stroke
				(width 0)
				(type default)
			)
			(fill no)
			(layer "F.CrtYd")
		)
		(fp_rect
			(start -0.508 0.9398)
			(end 0.508 -0.9398)
			(stroke
				(width 0)
				(type default)
			)
			(fill no)
			(layer "F.Fab")
		)
		(pad "1" smd custom
			(at 0 -0.4445)
			(size 0.1397 0.1397)
			(layers "F.Cu" "F.Mask" "F.Paste")
			(net "SW_PWR_R_HDD23")
			(options
				(clearance outline)
				(anchor circle)
			)
			(primitives
				(gr_poly
					(pts
						(arc
							(start -0.1778 -0.2794)
							(mid -0.249642 -0.249642)
							(end -0.2794 -0.1778)
						)
						(arc
							(start -0.2794 0.1778)
							(mid -0.249642 0.249642)
							(end -0.1778 0.2794)
						)
						(arc
							(start 0.1778 0.2794)
							(mid 0.249642 0.249642)
							(end 0.2794 0.1778)
						)
						(arc
							(start 0.2794 -0.1778)
							(mid 0.249642 -0.249642)
							(end 0.1778 -0.2794)
						)
					)
					(width 0)
					(fill yes)
				)
			)
		)
		(pad "2" smd custom
			(at 0 0.4445)
			(size 0.1397 0.1397)
			(layers "F.Cu" "F.Mask" "F.Paste")
			(net "GND")
			(options
				(clearance outline)
				(anchor circle)
			)
			(primitives
				(gr_poly
					(pts
						(arc
							(start -0.1778 -0.2794)
							(mid -0.249642 -0.249642)
							(end -0.2794 -0.1778)
						)
						(arc
							(start -0.2794 0.1778)
							(mid -0.249642 0.249642)
							(end -0.1778 0.2794)
						)
						(arc
							(start 0.1778 0.2794)
							(mid 0.249642 0.249642)
							(end 0.2794 0.1778)
						)
						(arc
							(start 0.2794 -0.1778)
							(mid 0.249642 -0.249642)
							(end 0.1778 -0.2794)
						)
					)
					(width 0)
					(fill yes)
				)
			)
		)
	)
	(footprint ""
		(layer "F.Cu")
		(at 468.122 -137.033 180)
		(property "Reference" "R615"
			(at 0 0 180)
			(layer "F.SilkS")
			(hide yes)
			(effects
				(font
					(size 1.27 1.27)
				)
			)
		)
		(property "Value" "200KR2F-L-GP"
			(at 0.064008 -3.993896 180)
			(unlocked yes)
			(layer "F.Fab")
			(hide yes)
			(effects
				(font
					(size 1.016 1.016)
					(thickness 0.1524)
				)
			)
		)
		(property "Device Type" "R402H16"
			(at 0.064008 -5.517896 180)
			(unlocked yes)
			(layer "F.Fab")
			(hide yes)
			(effects
				(font
					(size 1.016 1.016)
					(thickness 0.1524)
				)
			)
		)
		(duplicate_pad_numbers_are_jumpers no)
		(fp_line
			(start 0.508 -0.9398)
			(end -0.508 -0.9398)
			(stroke
				(width 0.1524)
				(type default)
			)
			(layer "F.SilkS")
		)
		(fp_line
			(start -0.508 -0.9398)
			(end -0.508 0.9398)
			(stroke
				(width 0.1524)
				(type default)
			)
			(layer "F.SilkS")
		)
		(fp_rect
			(start -0.508 0.9398)
			(end 0.508 -0.9398)
			(stroke
				(width 0)
				(type default)
			)
			(fill no)
			(layer "F.CrtYd")
		)
		(fp_rect
			(start -0.508 0.9398)
			(end 0.508 -0.9398)
			(stroke
				(width 0)
				(type default)
			)
			(fill no)
			(layer "F.Fab")
		)
		(pad "1" smd custom
			(at 0 -0.4445 180)
			(size 0.1397 0.1397)
			(layers "F.Cu" "F.Mask" "F.Paste")
			(net "SW_HDD_R23")
			(options
				(clearance outline)
				(anchor circle)
			)
			(primitives
				(gr_poly
					(pts
						(arc
							(start -0.1778 -0.2794)
							(mid -0.249642 -0.249642)
							(end -0.2794 -0.1778)
						)
						(arc
							(start -0.2794 0.1778)
							(mid -0.249642 0.249642)
							(end -0.1778 0.2794)
						)
						(arc
							(start 0.1778 0.2794)
							(mid 0.249642 0.249642)
							(end 0.2794 0.1778)
						)
						(arc
							(start 0.2794 -0.1778)
							(mid 0.249642 -0.249642)
							(end 0.1778 -0.2794)
						)
					)
					(width 0)
					(fill yes)
				)
			)
		)
		(pad "2" smd custom
			(at 0 0.4445 180)
			(size 0.1397 0.1397)
			(layers "F.Cu" "F.Mask" "F.Paste")
			(net "SW_HDD_N23")
			(options
				(clearance outline)
				(anchor circle)
			)
			(primitives
				(gr_poly
					(pts
						(arc
							(start -0.1778 -0.2794)
							(mid -0.249642 -0.249642)
							(end -0.2794 -0.1778)
						)
						(arc
							(start -0.2794 0.1778)
							(mid -0.249642 0.249642)
							(end -0.1778 0.2794)
						)
						(arc
							(start 0.1778 0.2794)
							(mid 0.249642 0.249642)
							(end 0.2794 0.1778)
						)
						(arc
							(start 0.2794 -0.1778)
							(mid 0.249642 -0.249642)
							(end 0.1778 -0.2794)
						)
					)
					(width 0)
					(fill yes)
				)
			)
		)
	)
	(footprint ""
		(layer "F.Cu")
		(at 111.76 -214.249)
		(property "Reference" "R253"
			(at 0 0 0)
			(layer "F.SilkS")
			(hide yes)
			(effects
				(font
					(size 1.27 1.27)
				)
			)
		)
		(property "Value" "130R3F-GP"
			(at -0.0254 -2.5146 0)
			(unlocked yes)
			(layer "F.Fab")
			(hide yes)
			(effects
				(font
					(size 1.016 1.016)
					(thickness 0.1524)
				)
			)
		)
		(property "Device Type" "R603H22"
			(at -0.0254 -4.0386 0)
			(unlocked yes)
			(layer "F.Fab")
			(hide yes)
			(effects
				(font
					(size 1.016 1.016)
					(thickness 0.1524)
				)
			)
		)
		(duplicate_pad_numbers_are_jumpers no)
		(fp_line
			(start -0.4826 0)
			(end -0.2032 0)
			(stroke
				(width 0.2032)
				(type default)
			)
			(layer "F.SilkS")
		)
		(fp_line
			(start 0.2032 0)
			(end 0.4826 0)
			(stroke
				(width 0.2032)
				(type default)
			)
			(layer "F.SilkS")
		)
		(fp_rect
			(start -0.5842 1.3335)
			(end 0.5842 -1.3335)
			(stroke
				(width 0)
				(type default)
			)
			(fill no)
			(layer "F.CrtYd")
		)
		(fp_rect
			(start -0.5842 1.3335)
			(end 0.5842 -1.3335)
			(stroke
				(width 0)
				(type default)
			)
			(fill no)
			(layer "F.Fab")
		)
		(pad "1" smd custom
			(at 0 -0.762)
			(size 0.2159 0.2159)
			(layers "F.Cu" "F.Mask" "F.Paste")
			(net "P5V_B_1")
			(options
				(clearance outline)
				(anchor circle)
			)
			(primitives
				(gr_poly
					(pts
						(arc
							(start -0.3302 -0.4318)
							(mid -0.402042 -0.402042)
							(end -0.4318 -0.3302)
						)
						(arc
							(start -0.4318 0.3302)
							(mid -0.402042 0.402042)
							(end -0.3302 0.4318)
						)
						(arc
							(start 0.3302 0.4318)
							(mid 0.402042 0.402042)
							(end 0.4318 0.3302)
						)
						(arc
							(start 0.4318 -0.3302)
							(mid 0.402042 -0.402042)
							(end 0.3302 -0.4318)
						)
					)
					(width 0)
					(fill yes)
				)
			)
		)
		(pad "2" smd custom
			(at 0 0.762)
			(size 0.2159 0.2159)
			(layers "F.Cu" "F.Mask" "F.Paste")
			(net "FLT_HDD3")
			(options
				(clearance outline)
				(anchor circle)
			)
			(primitives
				(gr_poly
					(pts
						(arc
							(start -0.3302 -0.4318)
							(mid -0.402042 -0.402042)
							(end -0.4318 -0.3302)
						)
						(arc
							(start -0.4318 0.3302)
							(mid -0.402042 0.402042)
							(end -0.3302 0.4318)
						)
						(arc
							(start 0.3302 0.4318)
							(mid 0.402042 0.402042)
							(end 0.4318 0.3302)
						)
						(arc
							(start 0.4318 -0.3302)
							(mid 0.402042 -0.402042)
							(end 0.3302 -0.4318)
						)
					)
					(width 0)
					(fill yes)
				)
			)
		)
	)
	(footprint ""
		(layer "F.Cu")
		(at 307.068982 -332.979776 180)
		(property "Reference" "C26"
			(at 0 0 180)
			(layer "F.SilkS")
			(hide yes)
			(effects
				(font
					(size 1.27 1.27)
				)
			)
		)
		(property "Value" "SCD1U16V2KX-3GP"
			(at 1.1811 -2.7051 180)
			(unlocked yes)
			(layer "F.Fab")
			(hide yes)
			(effects
				(font
					(size 1.016 1.016)
					(thickness 0.1524)
				)
			)
		)
		(property "Device Type" "C402H22"
			(at 1.1811 -4.2291 180)
			(unlocked yes)
			(layer "F.Fab")
			(hide yes)
			(effects
				(font
					(size 1.016 1.016)
					(thickness 0.1524)
				)
			)
		)
		(duplicate_pad_numbers_are_jumpers no)
		(fp_rect
			(start -0.4318 0.9525)
			(end 0.4318 -0.9525)
			(stroke
				(width 0)
				(type default)
			)
			(fill no)
			(layer "F.CrtYd")
		)
		(fp_rect
			(start -0.4318 0.9525)
			(end 0.4318 -0.9525)
			(stroke
				(width 0)
				(type default)
			)
			(fill no)
			(layer "F.Fab")
		)
		(pad "1" smd custom
			(at 0 -0.4445 180)
			(size 0.1524 0.1524)
			(layers "F.Cu" "F.Mask" "F.Paste")
			(net "P3V3_IN")
			(options
				(clearance outline)
				(anchor circle)
			)
			(primitives
				(gr_poly
					(pts
						(arc
							(start 0.3048 -0.2032)
							(mid 0.275042 -0.275042)
							(end 0.2032 -0.3048)
						)
						(arc
							(start -0.2032 -0.3048)
							(mid -0.275042 -0.275042)
							(end -0.3048 -0.2032)
						)
						(arc
							(start -0.3048 0.2032)
							(mid -0.275042 0.275042)
							(end -0.2032 0.3048)
						)
						(arc
							(start 0.2032 0.3048)
							(mid 0.275042 0.275042)
							(end 0.3048 0.2032)
						)
					)
					(width 0)
					(fill yes)
				)
			)
		)
		(pad "2" smd custom
			(at 0 0.4445 180)
			(size 0.1524 0.1524)
			(layers "F.Cu" "F.Mask" "F.Paste")
			(net "GND")
			(options
				(clearance outline)
				(anchor circle)
			)
			(primitives
				(gr_poly
					(pts
						(arc
							(start 0.3048 -0.2032)
							(mid 0.275042 -0.275042)
							(end 0.2032 -0.3048)
						)
						(arc
							(start -0.2032 -0.3048)
							(mid -0.275042 -0.275042)
							(end -0.3048 -0.2032)
						)
						(arc
							(start -0.3048 0.2032)
							(mid -0.275042 0.275042)
							(end -0.2032 0.3048)
						)
						(arc
							(start 0.2032 0.3048)
							(mid 0.275042 0.275042)
							(end 0.3048 0.2032)
						)
					)
					(width 0)
					(fill yes)
				)
			)
		)
	)
	(footprint ""
		(layer "F.Cu")
		(at 158.663386 -130.21945 90)
		(property "Reference" "C236"
			(at 0 0 90)
			(layer "F.SilkS")
			(hide yes)
			(effects
				(font
					(size 1.27 1.27)
				)
			)
		)
		(property "Value" "SCD01U16V1KX-GP"
			(at -2.8321 -1.7399 90)
			(unlocked yes)
			(layer "F.Fab")
			(hide yes)
			(effects
				(font
					(size 1.016 1.016)
					(thickness 0.1524)
				)
			)
		)
		(property "Device Type" "C0201H13"
			(at -2.8321 -3.2639 90)
			(unlocked yes)
			(layer "F.Fab")
			(hide yes)
			(effects
				(font
					(size 1.016 1.016)
					(thickness 0.1524)
				)
			)
		)
		(duplicate_pad_numbers_are_jumpers no)
		(fp_rect
			(start -0.2794 0.6477)
			(end 0.2794 -0.6477)
			(stroke
				(width 0)
				(type default)
			)
			(fill no)
			(layer "F.CrtYd")
		)
		(fp_rect
			(start -0.2794 0.6477)
			(end 0.2794 -0.6477)
			(stroke
				(width 0)
				(type default)
			)
			(fill no)
			(layer "F.Fab")
		)
		(pad "1" smd custom
			(at 0 -0.2794 90)
			(size 0.0762 0.0762)
			(layers "F.Cu" "F.Mask" "F.Paste")
			(net "SAS_HDD_RX_N16")
			(options
				(clearance outline)
				(anchor circle)
			)
			(primitives
				(gr_poly
					(pts
						(arc
							(start 0.1524 -0.127)
							(mid 0.137521 -0.162921)
							(end 0.1016 -0.1778)
						)
						(arc
							(start -0.1016 -0.1778)
							(mid -0.137521 -0.162921)
							(end -0.1524 -0.127)
						)
						(arc
							(start -0.1524 0.127)
							(mid -0.137521 0.162921)
							(end -0.1016 0.1778)
						)
						(arc
							(start 0.1016 0.1778)
							(mid 0.137521 0.162921)
							(end 0.1524 0.127)
						)
					)
					(width 0)
					(fill yes)
				)
			)
		)
		(pad "2" smd custom
			(at 0 0.2794 90)
			(size 0.0762 0.0762)
			(layers "F.Cu" "F.Mask" "F.Paste")
			(net "PHY_SCC_B_TO_DRV_B_16_DN")
			(options
				(clearance outline)
				(anchor circle)
			)
			(primitives
				(gr_poly
					(pts
						(arc
							(start 0.1524 -0.127)
							(mid 0.137521 -0.162921)
							(end 0.1016 -0.1778)
						)
						(arc
							(start -0.1016 -0.1778)
							(mid -0.137521 -0.162921)
							(end -0.1524 -0.127)
						)
						(arc
							(start -0.1524 0.127)
							(mid -0.137521 0.162921)
							(end -0.1016 0.1778)
						)
						(arc
							(start 0.1016 0.1778)
							(mid 0.137521 0.162921)
							(end 0.1524 0.127)
						)
					)
					(width 0)
					(fill yes)
				)
			)
		)
	)
)
